(kicad_pcb
	(version 20260206)
	(generator "pcbnew")
	(generator_version "10.0")
	(general
		(thickness 1.6)
		(legacy_teardrops no)
	)
	(paper "A4")
	(title_block
		(title "03242023_DA0F0TMBIJ0_F0T_Motherboard_J_brd_V01_OCP.brd")
		(comment 1 "Grand Teton / footprints 5563-5569 of 6105")
	)
	(layers
		(0 "F.Cu" signal "TOP")
		(4 "In1.Cu" signal "GND")
		(6 "In2.Cu" signal "IN1")
		(8 "In3.Cu" signal "GND1")
		(10 "In4.Cu" signal "IN2")
		(12 "In5.Cu" signal "GND2")
		(14 "In6.Cu" signal "IN3")
		(16 "In7.Cu" signal "GND3")
		(18 "In8.Cu" signal "VCC")
		(20 "In9.Cu" signal "VCC1")
		(22 "In10.Cu" signal "GND4")
		(24 "In11.Cu" signal "IN4")
		(26 "In12.Cu" signal "GND5")
		(28 "In13.Cu" signal "IN5")
		(30 "In14.Cu" signal "GND6")
		(32 "In15.Cu" signal "IN6")
		(34 "In16.Cu" signal "GND7")
		(2 "B.Cu" signal "BOTTOM")
		(9 "F.Adhes" user "F.Adhesive")
		(11 "B.Adhes" user "B.Adhesive")
		(13 "F.Paste" user "Package Geometry/Pastemask Top")
		(15 "B.Paste" user "Package Geometry/Pastemask Bottom")
		(5 "F.SilkS" user "Ref Des/Silkscreen Top")
		(7 "B.SilkS" user "Ref Des/Silkscreen Bottom")
		(1 "F.Mask" user "Board Geometry/Soldermask Top")
		(3 "B.Mask" user "Board Geometry/Soldermask Bottom")
		(17 "Dwgs.User" user "User.Drawings")
		(19 "Cmts.User" user "User.Comments")
		(21 "Eco1.User" user "User.Eco1")
		(23 "Eco2.User" user "User.Eco2")
		(25 "Edge.Cuts" user "Board Geometry/Outline")
		(27 "Margin" user)
		(31 "F.CrtYd" user "Package Geometry/Place Bound Top")
		(29 "B.CrtYd" user "Package Geometry/Place Bound Bottom")
		(35 "F.Fab" user "Ref Des/Assembly Top")
		(33 "B.Fab" user "Ref Des/Assembly Bottom")
	)
	(footprint ""
		(layer "B.Cu")
		(at 326.338438 -188.89599 -90)
		(property "Reference" "R6"
			(at 0 0 90)
			(layer "B.SilkS")
			(hide yes)
			(effects
				(font
					(size 1.27 1.27)
				)
				(justify mirror)
			)
		)
		(property "Value" ""
			(at 0 0 90)
			(layer "B.Fab")
			(effects
				(font
					(size 1.27 1.27)
				)
				(justify mirror)
			)
		)
		(duplicate_pad_numbers_are_jumpers no)
		(fp_line
			(start -0.7874 0.4064)
			(end 0.7874 0.4064)
			(stroke
				(width 0.1524)
				(type default)
			)
			(layer "B.SilkS")
		)
		(fp_line
			(start 0.7874 0.4064)
			(end 0.7874 -0.4064)
			(stroke
				(width 0.1524)
				(type default)
			)
			(layer "B.SilkS")
		)
		(fp_line
			(start -0.7874 -0.4064)
			(end -0.7874 0.4064)
			(stroke
				(width 0.1524)
				(type default)
			)
			(layer "B.SilkS")
		)
		(fp_line
			(start 0.7874 -0.4064)
			(end -0.7874 -0.4064)
			(stroke
				(width 0.1524)
				(type default)
			)
			(layer "B.SilkS")
		)
		(fp_line
			(start -0.67945 0.3048)
			(end -0.120396 0.3048)
			(stroke
				(width 0.1)
				(type default)
			)
			(layer "B.Fab")
		)
		(fp_line
			(start -0.120396 0.3048)
			(end -0.120396 0.2794)
			(stroke
				(width 0.1)
				(type default)
			)
			(layer "B.Fab")
		)
		(fp_line
			(start 0.12065 0.3048)
			(end 0.67945 0.3048)
			(stroke
				(width 0.1)
				(type default)
			)
			(layer "B.Fab")
		)
		(fp_line
			(start 0.67945 0.3048)
			(end 0.67945 -0.305054)
			(stroke
				(width 0.1)
				(type default)
			)
			(layer "B.Fab")
		)
		(fp_line
			(start -0.120396 0.2794)
			(end 0.12065 0.2794)
			(stroke
				(width 0.1)
				(type default)
			)
			(layer "B.Fab")
		)
		(fp_line
			(start 0.12065 0.2794)
			(end 0.12065 0.3048)
			(stroke
				(width 0.1)
				(type default)
			)
			(layer "B.Fab")
		)
		(fp_line
			(start -0.12065 -0.2794)
			(end -0.12065 -0.3048)
			(stroke
				(width 0.1)
				(type default)
			)
			(layer "B.Fab")
		)
		(fp_line
			(start 0.12065 -0.2794)
			(end -0.12065 -0.2794)
			(stroke
				(width 0.1)
				(type default)
			)
			(layer "B.Fab")
		)
		(fp_line
			(start -0.67945 -0.3048)
			(end -0.67945 0.3048)
			(stroke
				(width 0.1)
				(type default)
			)
			(layer "B.Fab")
		)
		(fp_line
			(start -0.12065 -0.3048)
			(end -0.67945 -0.3048)
			(stroke
				(width 0.1)
				(type default)
			)
			(layer "B.Fab")
		)
		(fp_line
			(start 0.12065 -0.305054)
			(end 0.12065 -0.2794)
			(stroke
				(width 0.1)
				(type default)
			)
			(layer "B.Fab")
		)
		(fp_line
			(start 0.67945 -0.305054)
			(end 0.12065 -0.305054)
			(stroke
				(width 0.1)
				(type default)
			)
			(layer "B.Fab")
		)
		(pad "1" smd circle
			(at 0.40005 0 90)
			(size 0 0)
			(layers "B.Cu" "B.Mask" "B.Paste")
			(net "JTAG_DBP_CPU_QS_GTL_TMS")
		)
		(pad "2" smd circle
			(at -0.40005 0 90)
			(size 0 0)
			(layers "B.Cu" "B.Mask" "B.Paste")
			(net "JTAG_DBP_CPU0_QS_GTL_R_TMS")
		)
	)
	(footprint ""
		(layer "B.Cu")
		(at 356.785418 -296.054526 180)
		(property "Reference" "C390"
			(at 0 0 0)
			(layer "B.SilkS")
			(hide yes)
			(effects
				(font
					(size 1.27 1.27)
				)
				(justify mirror)
			)
		)
		(property "Value" ""
			(at 0 0 0)
			(layer "B.Fab")
			(effects
				(font
					(size 1.27 1.27)
				)
				(justify mirror)
			)
		)
		(duplicate_pad_numbers_are_jumpers no)
		(fp_line
			(start 1.524 0.762)
			(end 1.524 -0.762)
			(stroke
				(width 0.1524)
				(type default)
			)
			(layer "B.SilkS")
		)
		(fp_line
			(start 1.524 -0.762)
			(end -1.524 -0.762)
			(stroke
				(width 0.1524)
				(type default)
			)
			(layer "B.SilkS")
		)
		(fp_line
			(start -1.524 0.762)
			(end 1.524 0.762)
			(stroke
				(width 0.1524)
				(type default)
			)
			(layer "B.SilkS")
		)
		(fp_line
			(start -1.524 -0.762)
			(end -1.524 0.762)
			(stroke
				(width 0.1524)
				(type default)
			)
			(layer "B.SilkS")
		)
		(fp_line
			(start 1.1049 0.724916)
			(end -1.1049 0.724916)
			(stroke
				(width 0.1)
				(type default)
			)
			(layer "B.Fab")
		)
		(fp_line
			(start 1.1049 -0.724916)
			(end 1.1049 0.724916)
			(stroke
				(width 0.1)
				(type default)
			)
			(layer "B.Fab")
		)
		(fp_line
			(start -1.1049 0.724916)
			(end -1.1049 -0.724916)
			(stroke
				(width 0.1)
				(type default)
			)
			(layer "B.Fab")
		)
		(fp_line
			(start -1.1049 -0.724916)
			(end 1.1049 -0.724916)
			(stroke
				(width 0.1)
				(type default)
			)
			(layer "B.Fab")
		)
		(pad "1" smd rect
			(at 0.889 0 180)
			(size 1.016 1.27)
			(layers "B.Cu" "B.Mask" "B.Paste")
			(net "PVCCIN_CPU0")
		)
		(pad "2" smd rect
			(at -0.889 0 180)
			(size 1.016 1.27)
			(layers "B.Cu" "B.Mask" "B.Paste")
			(net "GND")
		)
	)
	(footprint ""
		(layer "B.Cu")
		(at 408.807158 -258.318254 -90)
		(property "Reference" "C498"
			(at 0 0 90)
			(layer "B.SilkS")
			(hide yes)
			(effects
				(font
					(size 1.27 1.27)
				)
				(justify mirror)
			)
		)
		(property "Value" ""
			(at 0 0 90)
			(layer "B.Fab")
			(effects
				(font
					(size 1.27 1.27)
				)
				(justify mirror)
			)
		)
		(duplicate_pad_numbers_are_jumpers no)
		(fp_line
			(start -1.524 0.762)
			(end 1.524 0.762)
			(stroke
				(width 0.1524)
				(type default)
			)
			(layer "B.SilkS")
		)
		(fp_line
			(start 1.524 0.762)
			(end 1.524 -0.762)
			(stroke
				(width 0.1524)
				(type default)
			)
			(layer "B.SilkS")
		)
		(fp_line
			(start -1.524 -0.762)
			(end -1.524 0.762)
			(stroke
				(width 0.1524)
				(type default)
			)
			(layer "B.SilkS")
		)
		(fp_line
			(start 1.524 -0.762)
			(end -1.524 -0.762)
			(stroke
				(width 0.1524)
				(type default)
			)
			(layer "B.SilkS")
		)
		(fp_line
			(start -1.1049 0.724916)
			(end -1.1049 -0.724916)
			(stroke
				(width 0.1)
				(type default)
			)
			(layer "B.Fab")
		)
		(fp_line
			(start 1.1049 0.724916)
			(end -1.1049 0.724916)
			(stroke
				(width 0.1)
				(type default)
			)
			(layer "B.Fab")
		)
		(fp_line
			(start -1.1049 -0.724916)
			(end 1.1049 -0.724916)
			(stroke
				(width 0.1)
				(type default)
			)
			(layer "B.Fab")
		)
		(fp_line
			(start 1.1049 -0.724916)
			(end 1.1049 0.724916)
			(stroke
				(width 0.1)
				(type default)
			)
			(layer "B.Fab")
		)
		(pad "1" smd rect
			(at 0.889 0 270)
			(size 1.016 1.27)
			(layers "B.Cu" "B.Mask" "B.Paste")
			(net "PVCCFA_EHV_FIVRA_CPU0")
		)
		(pad "2" smd rect
			(at -0.889 0 270)
			(size 1.016 1.27)
			(layers "B.Cu" "B.Mask" "B.Paste")
			(net "GND")
		)
	)
	(footprint ""
		(layer "B.Cu")
		(at 190.80988 -130.266948 -90)
		(property "Reference" "R1473"
			(at 0 0 90)
			(layer "B.SilkS")
			(hide yes)
			(effects
				(font
					(size 1.27 1.27)
				)
				(justify mirror)
			)
		)
		(property "Value" ""
			(at 0 0 90)
			(layer "B.Fab")
			(effects
				(font
					(size 1.27 1.27)
				)
				(justify mirror)
			)
		)
		(duplicate_pad_numbers_are_jumpers no)
		(fp_line
			(start -0.7874 0.4064)
			(end 0.7874 0.4064)
			(stroke
				(width 0.1524)
				(type default)
			)
			(layer "B.SilkS")
		)
		(fp_line
			(start 0.7874 0.4064)
			(end 0.7874 -0.4064)
			(stroke
				(width 0.1524)
				(type default)
			)
			(layer "B.SilkS")
		)
		(fp_line
			(start -0.7874 -0.4064)
			(end -0.7874 0.4064)
			(stroke
				(width 0.1524)
				(type default)
			)
			(layer "B.SilkS")
		)
		(fp_line
			(start 0.7874 -0.4064)
			(end -0.7874 -0.4064)
			(stroke
				(width 0.1524)
				(type default)
			)
			(layer "B.SilkS")
		)
		(fp_line
			(start -0.67945 0.3048)
			(end -0.120396 0.3048)
			(stroke
				(width 0.1)
				(type default)
			)
			(layer "B.Fab")
		)
		(fp_line
			(start -0.120396 0.3048)
			(end -0.120396 0.2794)
			(stroke
				(width 0.1)
				(type default)
			)
			(layer "B.Fab")
		)
		(fp_line
			(start 0.12065 0.3048)
			(end 0.67945 0.3048)
			(stroke
				(width 0.1)
				(type default)
			)
			(layer "B.Fab")
		)
		(fp_line
			(start 0.67945 0.3048)
			(end 0.67945 -0.305054)
			(stroke
				(width 0.1)
				(type default)
			)
			(layer "B.Fab")
		)
		(fp_line
			(start -0.120396 0.2794)
			(end 0.12065 0.2794)
			(stroke
				(width 0.1)
				(type default)
			)
			(layer "B.Fab")
		)
		(fp_line
			(start 0.12065 0.2794)
			(end 0.12065 0.3048)
			(stroke
				(width 0.1)
				(type default)
			)
			(layer "B.Fab")
		)
		(fp_line
			(start -0.12065 -0.2794)
			(end -0.12065 -0.3048)
			(stroke
				(width 0.1)
				(type default)
			)
			(layer "B.Fab")
		)
		(fp_line
			(start 0.12065 -0.2794)
			(end -0.12065 -0.2794)
			(stroke
				(width 0.1)
				(type default)
			)
			(layer "B.Fab")
		)
		(fp_line
			(start -0.67945 -0.3048)
			(end -0.67945 0.3048)
			(stroke
				(width 0.1)
				(type default)
			)
			(layer "B.Fab")
		)
		(fp_line
			(start -0.12065 -0.3048)
			(end -0.67945 -0.3048)
			(stroke
				(width 0.1)
				(type default)
			)
			(layer "B.Fab")
		)
		(fp_line
			(start 0.12065 -0.305054)
			(end 0.12065 -0.2794)
			(stroke
				(width 0.1)
				(type default)
			)
			(layer "B.Fab")
		)
		(fp_line
			(start 0.67945 -0.305054)
			(end 0.12065 -0.305054)
			(stroke
				(width 0.1)
				(type default)
			)
			(layer "B.Fab")
		)
		(pad "1" smd circle
			(at 0.40005 0 90)
			(size 0 0)
			(layers "B.Cu" "B.Mask" "B.Paste")
			(net "FM_RST_PERST_BIT1")
		)
		(pad "2" smd circle
			(at -0.40005 0 90)
			(size 0 0)
			(layers "B.Cu" "B.Mask" "B.Paste")
			(net "P3V3_AUX")
		)
	)
	(footprint ""
		(layer "B.Cu")
		(at 447.771012 -58.325512 -90)
		(property "Reference" "PC1600"
			(at 0 0 90)
			(layer "B.SilkS")
			(hide yes)
			(effects
				(font
					(size 1.27 1.27)
				)
				(justify mirror)
			)
		)
		(property "Value" ""
			(at 0 0 90)
			(layer "B.Fab")
			(effects
				(font
					(size 1.27 1.27)
				)
				(justify mirror)
			)
		)
		(duplicate_pad_numbers_are_jumpers no)
		(fp_line
			(start -1.524 0.762)
			(end 1.524 0.762)
			(stroke
				(width 0.1524)
				(type default)
			)
			(layer "B.SilkS")
		)
		(fp_line
			(start 1.524 0.762)
			(end 1.524 -0.762)
			(stroke
				(width 0.1524)
				(type default)
			)
			(layer "B.SilkS")
		)
		(fp_line
			(start -1.524 -0.762)
			(end -1.524 0.762)
			(stroke
				(width 0.1524)
				(type default)
			)
			(layer "B.SilkS")
		)
		(fp_line
			(start 1.524 -0.762)
			(end -1.524 -0.762)
			(stroke
				(width 0.1524)
				(type default)
			)
			(layer "B.SilkS")
		)
		(fp_line
			(start -1.1049 0.724916)
			(end -1.1049 -0.724916)
			(stroke
				(width 0.1)
				(type default)
			)
			(layer "B.Fab")
		)
		(fp_line
			(start 1.1049 0.724916)
			(end -1.1049 0.724916)
			(stroke
				(width 0.1)
				(type default)
			)
			(layer "B.Fab")
		)
		(fp_line
			(start -1.1049 -0.724916)
			(end 1.1049 -0.724916)
			(stroke
				(width 0.1)
				(type default)
			)
			(layer "B.Fab")
		)
		(fp_line
			(start 1.1049 -0.724916)
			(end 1.1049 0.724916)
			(stroke
				(width 0.1)
				(type default)
			)
			(layer "B.Fab")
		)
		(pad "1" smd rect
			(at 0.889 0 270)
			(size 1.016 1.27)
			(layers "B.Cu" "B.Mask" "B.Paste")
			(net "P3V3_AUX")
		)
		(pad "2" smd rect
			(at -0.889 0 270)
			(size 1.016 1.27)
			(layers "B.Cu" "B.Mask" "B.Paste")
			(net "GND")
		)
	)
	(footprint ""
		(layer "B.Cu")
		(at 326.16648 -61.758068 -90)
		(property "Reference" "R1676"
			(at 0 0 90)
			(layer "B.SilkS")
			(hide yes)
			(effects
				(font
					(size 1.27 1.27)
				)
				(justify mirror)
			)
		)
		(property "Value" ""
			(at 0 0 90)
			(layer "B.Fab")
			(effects
				(font
					(size 1.27 1.27)
				)
				(justify mirror)
			)
		)
		(duplicate_pad_numbers_are_jumpers no)
		(fp_line
			(start -0.7874 0.4064)
			(end 0.7874 0.4064)
			(stroke
				(width 0.1524)
				(type default)
			)
			(layer "B.SilkS")
		)
		(fp_line
			(start 0.7874 0.4064)
			(end 0.7874 -0.4064)
			(stroke
				(width 0.1524)
				(type default)
			)
			(layer "B.SilkS")
		)
		(fp_line
			(start -0.7874 -0.4064)
			(end -0.7874 0.4064)
			(stroke
				(width 0.1524)
				(type default)
			)
			(layer "B.SilkS")
		)
		(fp_line
			(start 0.7874 -0.4064)
			(end -0.7874 -0.4064)
			(stroke
				(width 0.1524)
				(type default)
			)
			(layer "B.SilkS")
		)
		(fp_line
			(start -0.67945 0.3048)
			(end -0.120396 0.3048)
			(stroke
				(width 0.1)
				(type default)
			)
			(layer "B.Fab")
		)
		(fp_line
			(start -0.120396 0.3048)
			(end -0.120396 0.2794)
			(stroke
				(width 0.1)
				(type default)
			)
			(layer "B.Fab")
		)
		(fp_line
			(start 0.12065 0.3048)
			(end 0.67945 0.3048)
			(stroke
				(width 0.1)
				(type default)
			)
			(layer "B.Fab")
		)
		(fp_line
			(start 0.67945 0.3048)
			(end 0.67945 -0.305054)
			(stroke
				(width 0.1)
				(type default)
			)
			(layer "B.Fab")
		)
		(fp_line
			(start -0.120396 0.2794)
			(end 0.12065 0.2794)
			(stroke
				(width 0.1)
				(type default)
			)
			(layer "B.Fab")
		)
		(fp_line
			(start 0.12065 0.2794)
			(end 0.12065 0.3048)
			(stroke
				(width 0.1)
				(type default)
			)
			(layer "B.Fab")
		)
		(fp_line
			(start -0.12065 -0.2794)
			(end -0.12065 -0.3048)
			(stroke
				(width 0.1)
				(type default)
			)
			(layer "B.Fab")
		)
		(fp_line
			(start 0.12065 -0.2794)
			(end -0.12065 -0.2794)
			(stroke
				(width 0.1)
				(type default)
			)
			(layer "B.Fab")
		)
		(fp_line
			(start -0.67945 -0.3048)
			(end -0.67945 0.3048)
			(stroke
				(width 0.1)
				(type default)
			)
			(layer "B.Fab")
		)
		(fp_line
			(start -0.12065 -0.3048)
			(end -0.67945 -0.3048)
			(stroke
				(width 0.1)
				(type default)
			)
			(layer "B.Fab")
		)
		(fp_line
			(start 0.12065 -0.305054)
			(end 0.12065 -0.2794)
			(stroke
				(width 0.1)
				(type default)
			)
			(layer "B.Fab")
		)
		(fp_line
			(start 0.67945 -0.305054)
			(end 0.12065 -0.305054)
			(stroke
				(width 0.1)
				(type default)
			)
			(layer "B.Fab")
		)
		(pad "1" smd circle
			(at 0.40005 0 90)
			(size 0 0)
			(layers "B.Cu" "B.Mask" "B.Paste")
			(net "FM_PCIE_EV_BIF_EN")
		)
		(pad "2" smd circle
			(at -0.40005 0 90)
			(size 0 0)
			(layers "B.Cu" "B.Mask" "B.Paste")
			(net "GND")
		)
	)
	(footprint ""
		(layer "B.Cu")
		(at 428.164244 -122.085862 -90)
		(property "Reference" "PC813"
			(at 0 0 90)
			(layer "B.SilkS")
			(hide yes)
			(effects
				(font
					(size 1.27 1.27)
				)
				(justify mirror)
			)
		)
		(property "Value" ""
			(at 0 0 90)
			(layer "B.Fab")
			(effects
				(font
					(size 1.27 1.27)
				)
				(justify mirror)
			)
		)
		(duplicate_pad_numbers_are_jumpers no)
		(fp_line
			(start -0.7874 0.4064)
			(end 0.7874 0.4064)
			(stroke
				(width 0.1524)
				(type default)
			)
			(layer "B.SilkS")
		)
		(fp_line
			(start 0.7874 0.4064)
			(end 0.7874 -0.4064)
			(stroke
				(width 0.1524)
				(type default)
			)
			(layer "B.SilkS")
		)
		(fp_line
			(start -0.7874 -0.4064)
			(end -0.7874 0.4064)
			(stroke
				(width 0.1524)
				(type default)
			)
			(layer "B.SilkS")
		)
		(fp_line
			(start 0.7874 -0.4064)
			(end -0.7874 -0.4064)
			(stroke
				(width 0.1524)
				(type default)
			)
			(layer "B.SilkS")
		)
		(fp_line
			(start -0.67945 0.3048)
			(end -0.120396 0.3048)
			(stroke
				(width 0.1)
				(type default)
			)
			(layer "B.Fab")
		)
		(fp_line
			(start -0.120396 0.3048)
			(end -0.120396 0.2794)
			(stroke
				(width 0.1)
				(type default)
			)
			(layer "B.Fab")
		)
		(fp_line
			(start 0.12065 0.3048)
			(end 0.67945 0.3048)
			(stroke
				(width 0.1)
				(type default)
			)
			(layer "B.Fab")
		)
		(fp_line
			(start 0.67945 0.3048)
			(end 0.67945 -0.305054)
			(stroke
				(width 0.1)
				(type default)
			)
			(layer "B.Fab")
		)
		(fp_line
			(start -0.120396 0.2794)
			(end 0.12065 0.2794)
			(stroke
				(width 0.1)
				(type default)
			)
			(layer "B.Fab")
		)
		(fp_line
			(start 0.12065 0.2794)
			(end 0.12065 0.3048)
			(stroke
				(width 0.1)
				(type default)
			)
			(layer "B.Fab")
		)
		(fp_line
			(start -0.12065 -0.2794)
			(end -0.12065 -0.3048)
			(stroke
				(width 0.1)
				(type default)
			)
			(layer "B.Fab")
		)
		(fp_line
			(start 0.12065 -0.2794)
			(end -0.12065 -0.2794)
			(stroke
				(width 0.1)
				(type default)
			)
			(layer "B.Fab")
		)
		(fp_line
			(start -0.67945 -0.3048)
			(end -0.67945 0.3048)
			(stroke
				(width 0.1)
				(type default)
			)
			(layer "B.Fab")
		)
		(fp_line
			(start -0.12065 -0.3048)
			(end -0.67945 -0.3048)
			(stroke
				(width 0.1)
				(type default)
			)
			(layer "B.Fab")
		)
		(fp_line
			(start 0.12065 -0.305054)
			(end 0.12065 -0.2794)
			(stroke
				(width 0.1)
				(type default)
			)
			(layer "B.Fab")
		)
		(fp_line
			(start 0.67945 -0.305054)
			(end 0.12065 -0.305054)
			(stroke
				(width 0.1)
				(type default)
			)
			(layer "B.Fab")
		)
		(pad "1" smd circle
			(at 0.40005 0 90)
			(size 0 0)
			(layers "B.Cu" "B.Mask" "B.Paste")
			(net "PVCCD_HV_CPU0_ISENSE_N")
		)
		(pad "2" smd circle
			(at -0.40005 0 90)
			(size 0 0)
			(layers "B.Cu" "B.Mask" "B.Paste")
			(net "PVCCD_HV_CPU0_ISENSE_P")
		)
	)
)
